# BASEBOARD_FAB2 (Tioga Pass) — schematic netlist excerpt (pin names and nets, part order shuffled) for the footprints in the layout excerpt that follows; sources: Cadence DE-HDL packaged netlist, KiCad conversion of Wiwynn_Tioga_Pass_MB.brd

R9A14  RES  1.00K 1% CHIP  pkg 0402  page 111 : A = XDP_RST_CO_N ; B = P3V3_STBY
R2L6  RES  2.0K 1% CHIP  pkg 0402  page 178 : A = P3V3_STBY ; B = SGPIO_PCH_SSATA_CLOCK_R
C1E23  SC1U10V2KX-4-GP  10%  pkg SMD-BCG6  page 207 : \1\ = P5V_STBY ; \2\ = GND

(kicad_pcb
	(version 20260206)
	(generator "pcbnew")
	(generator_version "10.0")
	(general
		(thickness 1.6)
		(legacy_teardrops no)
	)
	(paper "A4")
	(title_block
		(title "Wiwynn_Tioga_Pass_MB.brd")
		(comment 1 "Tioga Pass / footprints 3213-3215 of 4770")
	)
	(layers
		(0 "F.Cu" signal "TOP")
		(4 "In1.Cu" signal "L2GND")
		(6 "In2.Cu" signal "L3")
		(8 "In3.Cu" signal "L4GND")
		(10 "In4.Cu" signal "L5")
		(12 "In5.Cu" signal "L6GND")
		(14 "In6.Cu" signal "L7VCC")
		(16 "In7.Cu" signal "L8VCC")
		(18 "In8.Cu" signal "L9GND")
		(20 "In9.Cu" signal "L10")
		(22 "In10.Cu" signal "L11GND")
		(24 "In11.Cu" signal "L12")
		(26 "In12.Cu" signal "L13GND")
		(2 "B.Cu" signal "BOTTOM")
		(9 "F.Adhes" user "F.Adhesive")
		(11 "B.Adhes" user "B.Adhesive")
		(13 "F.Paste" user "Package Geometry/Pastemask Top")
		(15 "B.Paste" user "Package Geometry/Pastemask Bottom")
		(5 "F.SilkS" user "Ref Des/Silkscreen Top")
		(7 "B.SilkS" user "Ref Des/Silkscreen Bottom")
		(1 "F.Mask" user "Board Geometry/Soldermask Top")
		(3 "B.Mask" user "Board Geometry/Soldermask Bottom")
		(17 "Dwgs.User" user "User.Drawings")
		(19 "Cmts.User" user "User.Comments")
		(21 "Eco1.User" user "User.Eco1")
		(23 "Eco2.User" user "User.Eco2")
		(25 "Edge.Cuts" user "Board Geometry/Outline")
		(27 "Margin" user)
		(31 "F.CrtYd" user "Package Geometry/Place Bound Top")
		(29 "B.CrtYd" user "Package Geometry/Place Bound Bottom")
		(35 "F.Fab" user "Ref Des/Assembly Top")
		(33 "B.Fab" user "Ref Des/Assembly Bottom")
	)
	(footprint ""
		(layer "B.Cu")
		(at 390.135364 -84.713572 180)
		(property "Reference" "R2L6"
			(at 0 0 0)
			(layer "B.SilkS")
			(hide yes)
			(effects
				(font
					(size 1.27 1.27)
				)
				(justify mirror)
			)
		)
		(property "Value" ""
			(at 0 0 0)
			(layer "B.Fab")
			(effects
				(font
					(size 1.27 1.27)
				)
				(justify mirror)
			)
		)
		(duplicate_pad_numbers_are_jumpers no)
		(fp_poly
			(pts
				(xy 0.2794 -0.1016) (xy -0.2794 -0.1016) (xy -0.2794 0.9906) (xy 0.2794 0.9906)
			)
			(stroke
				(width 0)
				(type default)
			)
			(fill no)
			(layer "B.CrtYd")
		)
		(fp_line
			(start 0.2794 0.9906)
			(end -0.2794 0.9906)
			(stroke
				(width 0.1)
				(type default)
			)
			(layer "B.Fab")
		)
		(fp_line
			(start 0.2794 -0.1016)
			(end 0.2794 0.9906)
			(stroke
				(width 0.1)
				(type default)
			)
			(layer "B.Fab")
		)
		(fp_line
			(start -0.2794 0.9906)
			(end -0.2794 -0.1016)
			(stroke
				(width 0.1)
				(type default)
			)
			(layer "B.Fab")
		)
		(fp_line
			(start -0.2794 -0.1016)
			(end 0.2794 -0.1016)
			(stroke
				(width 0.1)
				(type default)
			)
			(layer "B.Fab")
		)
		(pad "1" smd rect
			(at 0 0)
			(size 0.508 0.508)
			(layers "B.Cu" "B.Mask" "B.Paste")
			(net "P3V3_STBY")
		)
		(pad "2" smd rect
			(at 0 0.889)
			(size 0.508 0.508)
			(layers "B.Cu" "B.Mask" "B.Paste")
			(net "SGPIO_PCH_SSATA_CLOCK_R")
		)
		(zone
			(layer "B.Cu")
			(hatch none 0.5)
			(connect_pads
				(clearance 0)
			)
			(min_thickness 0.25)
			(keepout
				(tracks not_allowed)
				(vias allowed)
				(pads allowed)
				(copperpour not_allowed)
				(footprints allowed)
			)
			(placement
				(enabled no)
				(sheetname "")
			)
			(fill
				(thermal_gap 0.5)
				(thermal_bridge_width 0.5)
				(island_removal_mode 0)
			)
			(polygon
				(pts
					(xy 389.881364 -85.348572) (xy 390.389364 -85.348572) (xy 390.389364 -84.967572) (xy 389.881364 -84.967572)
				)
			)
		)
		(zone
			(layer "B.Cu")
			(hatch none 0.5)
			(connect_pads
				(clearance 0)
			)
			(min_thickness 0.25)
			(keepout
				(tracks allowed)
				(vias not_allowed)
				(pads allowed)
				(copperpour not_allowed)
				(footprints allowed)
			)
			(placement
				(enabled no)
				(sheetname "")
			)
			(fill
				(thermal_gap 0.5)
				(thermal_bridge_width 0.5)
				(island_removal_mode 0)
			)
			(polygon
				(pts
					(xy 389.881364 -84.967572) (xy 390.389364 -84.967572) (xy 390.389364 -85.348572) (xy 389.881364 -85.348572)
				)
			)
		)
	)
	(footprint ""
		(layer "B.Cu")
		(at 33.673796 -61.298582 90)
		(property "Reference" "C1E23"
			(at 0 0 90)
			(layer "B.SilkS")
			(hide yes)
			(effects
				(font
					(size 1.27 1.27)
				)
				(justify mirror)
			)
		)
		(property "Value" "*"
			(at -1.1811 -2.8194 90)
			(unlocked yes)
			(layer "B.Fab")
			(hide yes)
			(effects
				(font
					(size 1.27 1.016)
					(thickness 0.1524)
				)
				(justify mirror)
			)
		)
		(property "Device Type" "SC1U10V2KX-4-GP_SMD-BCG6-SC1U1A"
			(at -1.1811 -4.3434 90)
			(unlocked yes)
			(layer "B.Fab")
			(hide yes)
			(effects
				(font
					(size 1.27 1.016)
					(thickness 0.1524)
				)
				(justify mirror)
			)
		)
		(duplicate_pad_numbers_are_jumpers no)
		(fp_rect
			(start 0.4318 0.9525)
			(end -0.4318 -0.9525)
			(stroke
				(width 0)
				(type default)
			)
			(fill no)
			(layer "B.CrtYd")
		)
		(fp_rect
			(start 0.4318 0.9525)
			(end -0.4318 -0.9525)
			(stroke
				(width 0)
				(type default)
			)
			(fill no)
			(layer "B.Fab")
		)
		(pad "1" smd custom
			(at 0 -0.4445 270)
			(size 0.1524 0.1524)
			(layers "B.Cu" "B.Mask" "B.Paste")
			(net "P5V_STBY")
			(options
				(clearance outline)
				(anchor circle)
			)
			(primitives
				(gr_poly
					(pts
						(arc
							(start 0.3048 0.2032)
							(mid 0.275042 0.275042)
							(end 0.2032 0.3048)
						)
						(arc
							(start -0.2032 0.3048)
							(mid -0.275042 0.275042)
							(end -0.3048 0.2032)
						)
						(arc
							(start -0.3048 -0.2032)
							(mid -0.275042 -0.275042)
							(end -0.2032 -0.3048)
						)
						(arc
							(start 0.2032 -0.3048)
							(mid 0.275042 -0.275042)
							(end 0.3048 -0.2032)
						)
					)
					(width 0)
					(fill yes)
				)
			)
		)
		(pad "2" smd custom
			(at 0 0.4445 270)
			(size 0.1524 0.1524)
			(layers "B.Cu" "B.Mask" "B.Paste")
			(net "GND")
			(options
				(clearance outline)
				(anchor circle)
			)
			(primitives
				(gr_poly
					(pts
						(arc
							(start 0.3048 0.2032)
							(mid 0.275042 0.275042)
							(end 0.2032 0.3048)
						)
						(arc
							(start -0.2032 0.3048)
							(mid -0.275042 0.275042)
							(end -0.3048 0.2032)
						)
						(arc
							(start -0.3048 -0.2032)
							(mid -0.275042 -0.275042)
							(end -0.2032 -0.3048)
						)
						(arc
							(start 0.2032 -0.3048)
							(mid 0.275042 -0.275042)
							(end 0.3048 -0.2032)
						)
					)
					(width 0)
					(fill yes)
				)
			)
		)
	)
	(footprint ""
		(layer "B.Cu")
		(at 454.5838 -145.9738 -90)
		(property "Reference" "R9A14"
			(at 0 0 90)
			(layer "B.SilkS")
			(hide yes)
			(effects
				(font
					(size 1.27 1.27)
				)
				(justify mirror)
			)
		)
		(property "Value" ""
			(at 0 0 90)
			(layer "B.Fab")
			(effects
				(font
					(size 1.27 1.27)
				)
				(justify mirror)
			)
		)
		(duplicate_pad_numbers_are_jumpers no)
		(fp_poly
			(pts
				(xy 0.2794 -0.1016) (xy -0.2794 -0.1016) (xy -0.2794 0.9906) (xy 0.2794 0.9906)
			)
			(stroke
				(width 0)
				(type default)
			)
			(fill no)
			(layer "B.CrtYd")
		)
		(fp_line
			(start -0.2794 0.9906)
			(end -0.2794 -0.1016)
			(stroke
				(width 0.1)
				(type default)
			)
			(layer "B.Fab")
		)
		(fp_line
			(start 0.2794 0.9906)
			(end -0.2794 0.9906)
			(stroke
				(width 0.1)
				(type default)
			)
			(layer "B.Fab")
		)
		(fp_line
			(start -0.2794 -0.1016)
			(end 0.2794 -0.1016)
			(stroke
				(width 0.1)
				(type default)
			)
			(layer "B.Fab")
		)
		(fp_line
			(start 0.2794 -0.1016)
			(end 0.2794 0.9906)
			(stroke
				(width 0.1)
				(type default)
			)
			(layer "B.Fab")
		)
		(pad "1" smd rect
			(at 0 0 90)
			(size 0.508 0.508)
			(layers "B.Cu" "B.Mask" "B.Paste")
			(net "XDP_RST_CO_N")
		)
		(pad "2" smd rect
			(at 0 0.889 90)
			(size 0.508 0.508)
			(layers "B.Cu" "B.Mask" "B.Paste")
			(net "P3V3_STBY")
		)
		(zone
			(layer "B.Cu")
			(hatch none 0.5)
			(connect_pads
				(clearance 0)
			)
			(min_thickness 0.25)
			(keepout
				(tracks not_allowed)
				(vias allowed)
				(pads allowed)
				(copperpour not_allowed)
				(footprints allowed)
			)
			(placement
				(enabled no)
				(sheetname "")
			)
			(fill
				(thermal_gap 0.5)
				(thermal_bridge_width 0.5)
				(island_removal_mode 0)
			)
			(polygon
				(pts
					(xy 453.9488 -145.7198) (xy 453.9488 -146.2278) (xy 454.3298 -146.2278) (xy 454.3298 -145.7198)
				)
			)
		)
		(zone
			(layer "B.Cu")
			(hatch none 0.5)
			(connect_pads
				(clearance 0)
			)
			(min_thickness 0.25)
			(keepout
				(tracks allowed)
				(vias not_allowed)
				(pads allowed)
				(copperpour not_allowed)
				(footprints allowed)
			)
			(placement
				(enabled no)
				(sheetname "")
			)
			(fill
				(thermal_gap 0.5)
				(thermal_bridge_width 0.5)
				(island_removal_mode 0)
			)
			(polygon
				(pts
					(xy 454.3298 -145.7198) (xy 454.3298 -146.2278) (xy 453.9488 -146.2278) (xy 453.9488 -145.7198)
				)
			)
		)
	)
)
